# BASEBOARD_FAB2 (Tioga Pass) — schematic netlist excerpt (pin names and nets, part order shuffled) for the footprints in the layout excerpt that follows; sources: Cadence DE-HDL packaged netlist, KiCad conversion of Wiwynn_Tioga_Pass_MB.brd

C3B5  CAP_A  0.1UF 16V 10% X7R  pkg 0402V  page 99 : A = PVPP_KLM ; B = GND

Y3F1  OSC_C  156.25MHZ OSC  pkg 6P10  page 104
  ENABLE_DISABLE  = FM_CPU1_STL_BRD_OSC_EN
  NC_GND  = NC_CLK_156M_CPU1_OSC
  GND  = GND
  \out\  = CLK_156M_OSC_BRD_CPU1_DP
  OUT_N  = CLK_156M_OSC_BRD_CPU1_DN
  VCC  = P3V3

(kicad_pcb
	(version 20260206)
	(generator "pcbnew")
	(generator_version "10.0")
	(general
		(thickness 1.6)
		(legacy_teardrops no)
	)
	(paper "A4")
	(title_block
		(title "Wiwynn_Tioga_Pass_MB.brd")
		(comment 1 "Tioga Pass / footprints 1266-1267 of 4770")
	)
	(layers
		(0 "F.Cu" signal "TOP")
		(4 "In1.Cu" signal "L2GND")
		(6 "In2.Cu" signal "L3")
		(8 "In3.Cu" signal "L4GND")
		(10 "In4.Cu" signal "L5")
		(12 "In5.Cu" signal "L6GND")
		(14 "In6.Cu" signal "L7VCC")
		(16 "In7.Cu" signal "L8VCC")
		(18 "In8.Cu" signal "L9GND")
		(20 "In9.Cu" signal "L10")
		(22 "In10.Cu" signal "L11GND")
		(24 "In11.Cu" signal "L12")
		(26 "In12.Cu" signal "L13GND")
		(2 "B.Cu" signal "BOTTOM")
		(9 "F.Adhes" user "F.Adhesive")
		(11 "B.Adhes" user "B.Adhesive")
		(13 "F.Paste" user "Package Geometry/Pastemask Top")
		(15 "B.Paste" user "Package Geometry/Pastemask Bottom")
		(5 "F.SilkS" user "Ref Des/Silkscreen Top")
		(7 "B.SilkS" user "Ref Des/Silkscreen Bottom")
		(1 "F.Mask" user "Board Geometry/Soldermask Top")
		(3 "B.Mask" user "Board Geometry/Soldermask Bottom")
		(17 "Dwgs.User" user "User.Drawings")
		(19 "Cmts.User" user "User.Comments")
		(21 "Eco1.User" user "User.Eco1")
		(23 "Eco2.User" user "User.Eco2")
		(25 "Edge.Cuts" user "Board Geometry/Outline")
		(27 "Margin" user)
		(31 "F.CrtYd" user "Package Geometry/Place Bound Top")
		(29 "B.CrtYd" user "Package Geometry/Place Bound Bottom")
		(35 "F.Fab" user "Ref Des/Assembly Top")
		(33 "B.Fab" user "Ref Des/Assembly Bottom")
	)
	(footprint ""
		(layer "F.Cu")
		(at 159.87522 -125.1077 90)
		(property "Reference" "C3B5"
			(at 0 0 90)
			(layer "F.SilkS")
			(hide yes)
			(effects
				(font
					(size 1.27 1.27)
				)
			)
		)
		(property "Value" ""
			(at 0 0 90)
			(layer "F.Fab")
			(effects
				(font
					(size 1.27 1.27)
				)
			)
		)
		(duplicate_pad_numbers_are_jumpers no)
		(fp_poly
			(pts
				(xy 0.3048 -0.1016) (xy 0.3048 0.9906) (xy -0.3048 0.9906) (xy -0.3048 -0.1016)
			)
			(stroke
				(width 0)
				(type default)
			)
			(fill no)
			(layer "F.CrtYd")
		)
		(fp_line
			(start 0.3048 -0.1016)
			(end -0.3048 -0.1016)
			(stroke
				(width 0.1)
				(type default)
			)
			(layer "F.Fab")
		)
		(fp_line
			(start -0.3048 -0.1016)
			(end -0.3048 0.9906)
			(stroke
				(width 0.1)
				(type default)
			)
			(layer "F.Fab")
		)
		(fp_line
			(start 0.3048 0.9906)
			(end 0.3048 -0.1016)
			(stroke
				(width 0.1)
				(type default)
			)
			(layer "F.Fab")
		)
		(fp_line
			(start -0.3048 0.9906)
			(end 0.3048 0.9906)
			(stroke
				(width 0.1)
				(type default)
			)
			(layer "F.Fab")
		)
		(pad "1" smd rect
			(at 0 0 90)
			(size 0.508 0.508)
			(layers "F.Cu" "F.Mask" "F.Paste")
			(net "PVPP_KLM")
		)
		(pad "2" smd rect
			(at 0 0.889 90)
			(size 0.508 0.508)
			(layers "F.Cu" "F.Mask" "F.Paste")
			(net "GND")
		)
		(zone
			(layer "F.Cu")
			(hatch none 0.5)
			(connect_pads
				(clearance 0)
			)
			(min_thickness 0.25)
			(keepout
				(tracks allowed)
				(vias not_allowed)
				(pads allowed)
				(copperpour not_allowed)
				(footprints allowed)
			)
			(placement
				(enabled no)
				(sheetname "")
			)
			(fill
				(thermal_gap 0.5)
				(thermal_bridge_width 0.5)
				(island_removal_mode 0)
			)
			(polygon
				(pts
					(xy 160.12922 -124.8537) (xy 160.12922 -125.3617) (xy 160.51022 -125.3617) (xy 160.51022 -124.8537)
				)
			)
		)
		(zone
			(layer "F.Cu")
			(hatch none 0.5)
			(connect_pads
				(clearance 0)
			)
			(min_thickness 0.25)
			(keepout
				(tracks not_allowed)
				(vias allowed)
				(pads allowed)
				(copperpour not_allowed)
				(footprints allowed)
			)
			(placement
				(enabled no)
				(sheetname "")
			)
			(fill
				(thermal_gap 0.5)
				(thermal_bridge_width 0.5)
				(island_removal_mode 0)
			)
			(polygon
				(pts
					(xy 160.51022 -124.8537) (xy 160.51022 -125.3617) (xy 160.12922 -125.3617) (xy 160.12922 -124.8537)
				)
			)
		)
	)
	(footprint ""
		(layer "F.Cu")
		(at 149.7711 -31.1658)
		(property "Reference" "Y3F1"
			(at -0.0381 -2.08153 0)
			(unlocked yes)
			(layer "F.SilkS")
			(effects
				(font
					(size 0.7874 0.5842)
					(thickness 0.1524)
				)
				(justify left)
			)
		)
		(property "Value" ""
			(at 0 0 0)
			(layer "F.Fab")
			(effects
				(font
					(size 1.27 1.27)
				)
			)
		)
		(duplicate_pad_numbers_are_jumpers no)
		(fp_line
			(start -0.366522 -1.329944)
			(end 3.033522 -1.329944)
			(stroke
				(width 0.1524)
				(type default)
			)
			(layer "F.SilkS")
		)
		(fp_line
			(start -0.366522 -0.80391)
			(end -0.366522 -1.329944)
			(stroke
				(width 0.1524)
				(type default)
			)
			(layer "F.SilkS")
		)
		(fp_line
			(start -0.366522 3.869944)
			(end -0.366522 3.363468)
			(stroke
				(width 0.1524)
				(type default)
			)
			(layer "F.SilkS")
		)
		(fp_line
			(start 3.033522 -1.329944)
			(end 3.033522 -0.790956)
			(stroke
				(width 0.1524)
				(type default)
			)
			(layer "F.SilkS")
		)
		(fp_line
			(start 3.033522 3.370072)
			(end 3.033522 3.869944)
			(stroke
				(width 0.1524)
				(type default)
			)
			(layer "F.SilkS")
		)
		(fp_line
			(start 3.033522 3.869944)
			(end -0.366522 3.869944)
			(stroke
				(width 0.1524)
				(type default)
			)
			(layer "F.SilkS")
		)
		(fp_circle
			(center -1.914906 -0.701802)
			(end -1.787906 -0.701802)
			(stroke
				(width 0.254)
				(type default)
			)
			(fill no)
			(layer "F.SilkS")
		)
		(fp_rect
			(start -0.366522 3.869944)
			(end 3.033522 -1.329944)
			(stroke
				(width 0)
				(type default)
			)
			(fill no)
			(layer "F.CrtYd")
		)
		(fp_line
			(start -0.366522 -1.329944)
			(end 3.033522 -1.329944)
			(stroke
				(width 0.1)
				(type default)
			)
			(layer "F.Fab")
		)
		(fp_line
			(start -0.366522 3.869944)
			(end -0.366522 -1.329944)
			(stroke
				(width 0.1)
				(type default)
			)
			(layer "F.Fab")
		)
		(fp_line
			(start 3.033522 -1.329944)
			(end 3.033522 3.869944)
			(stroke
				(width 0.1)
				(type default)
			)
			(layer "F.Fab")
		)
		(fp_line
			(start 3.033522 3.869944)
			(end -0.366522 3.869944)
			(stroke
				(width 0.1)
				(type default)
			)
			(layer "F.Fab")
		)
		(fp_circle
			(center -1.913636 -0.708152)
			(end -1.786636 -0.708152)
			(stroke
				(width 0.254)
				(type default)
			)
			(fill no)
			(layer "F.Fab")
		)
		(pad "1" smd rect
			(at 0 0)
			(size 1.651 0.8382)
			(layers "F.Cu" "F.Mask" "F.Paste")
			(net "FM_CPU1_STL_BRD_OSC_EN")
		)
		(pad "2" smd rect
			(at 0 1.27)
			(size 1.651 0.8382)
			(layers "F.Cu" "F.Mask" "F.Paste")
			(net "NC_CLK_156M_CPU1_OSC")
		)
		(pad "3" smd rect
			(at 0 2.54)
			(size 1.651 0.8382)
			(layers "F.Cu" "F.Mask" "F.Paste")
			(net "GND")
		)
		(pad "4" smd rect
			(at 2.667 2.54)
			(size 1.651 0.8382)
			(layers "F.Cu" "F.Mask" "F.Paste")
			(net "CLK_156M_OSC_BRD_CPU1_DP")
		)
		(pad "5" smd rect
			(at 2.667 1.27)
			(size 1.651 0.8382)
			(layers "F.Cu" "F.Mask" "F.Paste")
			(net "CLK_156M_OSC_BRD_CPU1_DN")
		)
		(pad "6" smd rect
			(at 2.667 0)
			(size 1.651 0.8382)
			(layers "F.Cu" "F.Mask" "F.Paste")
			(net "P3V3")
		)
	)
)
